# BASEBOARD_FAB2 (Tioga Pass) — schematic netlist excerpt (pin names and nets, part order shuffled) for the footprints in the layout excerpt that follows; sources: Cadence DE-HDL packaged netlist, KiCad conversion of Wiwynn_Tioga_Pass_MB.brd

C4D35  CAP_A  0.1UF 16V 10% X7R  pkg 0402V  page 203 : A = VR_FET_SW_P12V_STBY_PVCCIN_CPU0 ; B = GND
C7G24  CAP  0.22UF 16V 10% X7R  pkg 0402  page 105 : A = P3E_CPU0_PE2_SS_TXN<6> ; B = P3E_CPU0_PE2_SS_C_TXN<6>
R1A2  RES  68.1K 1% EMPTY  pkg 0402  page 227 : A = VR_PVDDQ_KLM_PH2_OCSET ; B = GND

(kicad_pcb
	(version 20260206)
	(generator "pcbnew")
	(generator_version "10.0")
	(general
		(thickness 1.6)
		(legacy_teardrops no)
	)
	(paper "A4")
	(title_block
		(title "Wiwynn_Tioga_Pass_MB.brd")
		(comment 1 "Tioga Pass / footprints 876-878 of 4770")
	)
	(layers
		(0 "F.Cu" signal "TOP")
		(4 "In1.Cu" signal "L2GND")
		(6 "In2.Cu" signal "L3")
		(8 "In3.Cu" signal "L4GND")
		(10 "In4.Cu" signal "L5")
		(12 "In5.Cu" signal "L6GND")
		(14 "In6.Cu" signal "L7VCC")
		(16 "In7.Cu" signal "L8VCC")
		(18 "In8.Cu" signal "L9GND")
		(20 "In9.Cu" signal "L10")
		(22 "In10.Cu" signal "L11GND")
		(24 "In11.Cu" signal "L12")
		(26 "In12.Cu" signal "L13GND")
		(2 "B.Cu" signal "BOTTOM")
		(9 "F.Adhes" user "F.Adhesive")
		(11 "B.Adhes" user "B.Adhesive")
		(13 "F.Paste" user "Package Geometry/Pastemask Top")
		(15 "B.Paste" user "Package Geometry/Pastemask Bottom")
		(5 "F.SilkS" user "Ref Des/Silkscreen Top")
		(7 "B.SilkS" user "Ref Des/Silkscreen Bottom")
		(1 "F.Mask" user "Board Geometry/Soldermask Top")
		(3 "B.Mask" user "Board Geometry/Soldermask Bottom")
		(17 "Dwgs.User" user "User.Drawings")
		(19 "Cmts.User" user "User.Comments")
		(21 "Eco1.User" user "User.Eco1")
		(23 "Eco2.User" user "User.Eco2")
		(25 "Edge.Cuts" user "Board Geometry/Outline")
		(27 "Margin" user)
		(31 "F.CrtYd" user "Package Geometry/Place Bound Top")
		(29 "B.CrtYd" user "Package Geometry/Place Bound Bottom")
		(35 "F.Fab" user "Ref Des/Assembly Top")
		(33 "B.Fab" user "Ref Des/Assembly Bottom")
	)
	(footprint ""
		(layer "F.Cu")
		(at 396.468092 -10.968736)
		(property "Reference" "C7G24"
			(at 0 0 0)
			(layer "F.SilkS")
			(hide yes)
			(effects
				(font
					(size 1.27 1.27)
				)
			)
		)
		(property "Value" ""
			(at 0 0 0)
			(layer "F.Fab")
			(effects
				(font
					(size 1.27 1.27)
				)
			)
		)
		(duplicate_pad_numbers_are_jumpers no)
		(fp_rect
			(start -0.3048 0.9906)
			(end 0.3048 -0.1016)
			(stroke
				(width 0)
				(type default)
			)
			(fill no)
			(layer "F.CrtYd")
		)
		(fp_line
			(start -0.3048 -0.1016)
			(end -0.3048 0.9906)
			(stroke
				(width 0.1)
				(type default)
			)
			(layer "F.Fab")
		)
		(fp_line
			(start -0.3048 0.9906)
			(end 0.3048 0.9906)
			(stroke
				(width 0.1)
				(type default)
			)
			(layer "F.Fab")
		)
		(fp_line
			(start 0.3048 -0.1016)
			(end -0.3048 -0.1016)
			(stroke
				(width 0.1)
				(type default)
			)
			(layer "F.Fab")
		)
		(fp_line
			(start 0.3048 0.9906)
			(end 0.3048 -0.1016)
			(stroke
				(width 0.1)
				(type default)
			)
			(layer "F.Fab")
		)
		(pad "1" smd rect
			(at 0 0)
			(size 0.508 0.508)
			(layers "F.Cu" "F.Mask" "F.Paste")
			(net "P3E_CPU0_PE2_SS_TXN<6>")
		)
		(pad "2" smd rect
			(at 0 0.889)
			(size 0.508 0.508)
			(layers "F.Cu" "F.Mask" "F.Paste")
			(net "P3E_CPU0_PE2_SS_C_TXN<6>")
		)
		(zone
			(layer "F.Cu")
			(hatch none 0.5)
			(connect_pads
				(clearance 0)
			)
			(min_thickness 0.25)
			(keepout
				(tracks not_allowed)
				(vias allowed)
				(pads allowed)
				(copperpour not_allowed)
				(footprints allowed)
			)
			(placement
				(enabled no)
				(sheetname "")
			)
			(fill
				(thermal_gap 0.5)
				(thermal_bridge_width 0.5)
				(island_removal_mode 0)
			)
			(polygon
				(pts
					(xy 396.214092 -10.333736) (xy 396.722092 -10.333736) (xy 396.722092 -10.714736) (xy 396.214092 -10.714736)
				)
			)
		)
		(zone
			(layer "F.Cu")
			(hatch none 0.5)
			(connect_pads
				(clearance 0)
			)
			(min_thickness 0.25)
			(keepout
				(tracks allowed)
				(vias not_allowed)
				(pads allowed)
				(copperpour not_allowed)
				(footprints allowed)
			)
			(placement
				(enabled no)
				(sheetname "")
			)
			(fill
				(thermal_gap 0.5)
				(thermal_bridge_width 0.5)
				(island_removal_mode 0)
			)
			(polygon
				(pts
					(xy 396.214092 -10.333736) (xy 396.722092 -10.333736) (xy 396.722092 -10.714736) (xy 396.214092 -10.714736)
				)
			)
		)
	)
	(footprint ""
		(layer "F.Cu")
		(at 198.046594 -76.698856 90)
		(property "Reference" "C4D35"
			(at -0.8382 -0.67818 90)
			(unlocked yes)
			(layer "F.SilkS")
			(effects
				(font
					(size 0.4064 0.254)
					(thickness 0.1524)
				)
				(justify left)
			)
		)
		(property "Value" ""
			(at 0 0 90)
			(layer "F.Fab")
			(effects
				(font
					(size 1.27 1.27)
				)
			)
		)
		(duplicate_pad_numbers_are_jumpers no)
		(fp_poly
			(pts
				(xy 0.3048 -0.1016) (xy 0.3048 0.9906) (xy -0.3048 0.9906) (xy -0.3048 -0.1016)
			)
			(stroke
				(width 0)
				(type default)
			)
			(fill no)
			(layer "F.CrtYd")
		)
		(fp_line
			(start 0.3048 -0.1016)
			(end -0.3048 -0.1016)
			(stroke
				(width 0.1)
				(type default)
			)
			(layer "F.Fab")
		)
		(fp_line
			(start -0.3048 -0.1016)
			(end -0.3048 0.9906)
			(stroke
				(width 0.1)
				(type default)
			)
			(layer "F.Fab")
		)
		(fp_line
			(start 0.3048 0.9906)
			(end 0.3048 -0.1016)
			(stroke
				(width 0.1)
				(type default)
			)
			(layer "F.Fab")
		)
		(fp_line
			(start -0.3048 0.9906)
			(end 0.3048 0.9906)
			(stroke
				(width 0.1)
				(type default)
			)
			(layer "F.Fab")
		)
		(pad "1" smd rect
			(at 0 0 90)
			(size 0.508 0.508)
			(layers "F.Cu" "F.Mask" "F.Paste")
			(net "VR_FET_SW_P12V_STBY_PVCCIN_CPU0")
		)
		(pad "2" smd rect
			(at 0 0.889 90)
			(size 0.508 0.508)
			(layers "F.Cu" "F.Mask" "F.Paste")
			(net "GND")
		)
		(zone
			(layer "F.Cu")
			(hatch none 0.5)
			(connect_pads
				(clearance 0)
			)
			(min_thickness 0.25)
			(keepout
				(tracks allowed)
				(vias not_allowed)
				(pads allowed)
				(copperpour not_allowed)
				(footprints allowed)
			)
			(placement
				(enabled no)
				(sheetname "")
			)
			(fill
				(thermal_gap 0.5)
				(thermal_bridge_width 0.5)
				(island_removal_mode 0)
			)
			(polygon
				(pts
					(xy 198.300594 -76.444856) (xy 198.300594 -76.952856) (xy 198.681594 -76.952856) (xy 198.681594 -76.444856)
				)
			)
		)
		(zone
			(layer "F.Cu")
			(hatch none 0.5)
			(connect_pads
				(clearance 0)
			)
			(min_thickness 0.25)
			(keepout
				(tracks not_allowed)
				(vias allowed)
				(pads allowed)
				(copperpour not_allowed)
				(footprints allowed)
			)
			(placement
				(enabled no)
				(sheetname "")
			)
			(fill
				(thermal_gap 0.5)
				(thermal_bridge_width 0.5)
				(island_removal_mode 0)
			)
			(polygon
				(pts
					(xy 198.681594 -76.444856) (xy 198.681594 -76.952856) (xy 198.300594 -76.952856) (xy 198.300594 -76.444856)
				)
			)
		)
	)
	(footprint ""
		(layer "F.Cu")
		(at -3.175 -144.8562 -90)
		(property "Reference" "R1A2"
			(at 0 0 270)
			(layer "F.SilkS")
			(hide yes)
			(effects
				(font
					(size 1.27 1.27)
				)
			)
		)
		(property "Value" ""
			(at 0 0 270)
			(layer "F.Fab")
			(effects
				(font
					(size 1.27 1.27)
				)
			)
		)
		(duplicate_pad_numbers_are_jumpers no)
		(fp_poly
			(pts
				(xy -0.2794 -0.1016) (xy 0.2794 -0.1016) (xy 0.2794 0.9906) (xy -0.2794 0.9906)
			)
			(stroke
				(width 0)
				(type default)
			)
			(fill no)
			(layer "F.CrtYd")
		)
		(fp_line
			(start -0.2794 0.9906)
			(end 0.2794 0.9906)
			(stroke
				(width 0.1)
				(type default)
			)
			(layer "F.Fab")
		)
		(fp_line
			(start 0.2794 0.9906)
			(end 0.2794 -0.1016)
			(stroke
				(width 0.1)
				(type default)
			)
			(layer "F.Fab")
		)
		(fp_line
			(start -0.2794 -0.1016)
			(end -0.2794 0.9906)
			(stroke
				(width 0.1)
				(type default)
			)
			(layer "F.Fab")
		)
		(fp_line
			(start 0.2794 -0.1016)
			(end -0.2794 -0.1016)
			(stroke
				(width 0.1)
				(type default)
			)
			(layer "F.Fab")
		)
		(pad "1" smd rect
			(at 0 0 270)
			(size 0.508 0.508)
			(layers "F.Cu" "F.Mask" "F.Paste")
			(net "VR_PVDDQ_KLM_PH2_OCSET")
		)
		(pad "2" smd rect
			(at 0 0.889 270)
			(size 0.508 0.508)
			(layers "F.Cu" "F.Mask" "F.Paste")
			(net "GND")
		)
		(zone
			(layer "F.Cu")
			(hatch none 0.5)
			(connect_pads
				(clearance 0)
			)
			(min_thickness 0.25)
			(keepout
				(tracks not_allowed)
				(vias allowed)
				(pads allowed)
				(copperpour not_allowed)
				(footprints allowed)
			)
			(placement
				(enabled no)
				(sheetname "")
			)
			(fill
				(thermal_gap 0.5)
				(thermal_bridge_width 0.5)
				(island_removal_mode 0)
			)
			(polygon
				(pts
					(xy -3.81 -145.1102) (xy -3.81 -144.6022) (xy -3.429 -144.6022) (xy -3.429 -145.1102)
				)
			)
		)
		(zone
			(layer "F.Cu")
			(hatch none 0.5)
			(connect_pads
				(clearance 0)
			)
			(min_thickness 0.25)
			(keepout
				(tracks allowed)
				(vias not_allowed)
				(pads allowed)
				(copperpour not_allowed)
				(footprints allowed)
			)
			(placement
				(enabled no)
				(sheetname "")
			)
			(fill
				(thermal_gap 0.5)
				(thermal_bridge_width 0.5)
				(island_removal_mode 0)
			)
			(polygon
				(pts
					(xy -3.429 -145.1102) (xy -3.429 -144.6022) (xy -3.81 -144.6022) (xy -3.81 -145.1102)
				)
			)
		)
	)
)
